(kicad_pcb
	(version 20241229)
	(generator "pcbnew")
	(generator_version "9.0")
	(general
		(thickness 1.61)
		(legacy_teardrops no)
	)
	(paper "A3")
	(title_block
		(title "SO-DIMM DDR5 Tester")
		(date "2025-11-26")
		(rev "1.3.0")
		(comment 9 "footprints 203-207 of 627")
	)
	(layers
		(0 "F.Cu" signal)
		(4 "In1.Cu" power)
		(6 "In2.Cu" mixed)
		(8 "In3.Cu" power)
		(10 "In4.Cu" mixed)
		(12 "In5.Cu" power)
		(14 "In6.Cu" mixed)
		(16 "In7.Cu" power)
		(18 "In8.Cu" power)
		(20 "In9.Cu" mixed)
		(22 "In10.Cu" power)
		(2 "B.Cu" signal)
		(9 "F.Adhes" user "F.Adhesive")
		(11 "B.Adhes" user "B.Adhesive")
		(13 "F.Paste" user)
		(15 "B.Paste" user)
		(5 "F.SilkS" user "F.Silkscreen")
		(7 "B.SilkS" user "B.Silkscreen")
		(1 "F.Mask" user)
		(3 "B.Mask" user)
		(17 "Dwgs.User" user "User.Drawings")
		(19 "Cmts.User" user "User.Comments")
		(21 "Eco1.User" user "User.Eco1")
		(23 "Eco2.User" user "User.Eco2")
		(25 "Edge.Cuts" user)
		(27 "Margin" user)
		(31 "F.CrtYd" user "F.Courtyard")
		(29 "B.CrtYd" user "B.Courtyard")
		(35 "F.Fab" user)
		(33 "B.Fab" user)
	)
	(footprint "antmicro-footprints:C_0805_2012Metric"
		(layer "F.Cu")
		(at 203.331001 166.922 90)
		(descr "Capacitor SMD 0805")
		(tags "capacitor SMD 0805")
		(property "Reference" "C178"
			(at -2.10551 -1.198678 90)
			(layer "F.SilkS")
			(hide yes)
			(effects
				(font
					(size 0.7 0.7)
					(thickness 0.15)
				)
				(justify left bottom)
			)
		)
		(property "Value" "C_22u_25V_0805"
			(at -2.055717 1.963152 90)
			(layer "F.Fab")
			(effects
				(font
					(size 0.7 0.7)
					(thickness 0.15)
				)
				(justify left bottom)
			)
		)
		(property "Datasheet" "https://product.samsungsem.com/mlcc/CL21A226MAYNNN.do"
			(at 0 0 90)
			(layer "F.Fab")
			(hide yes)
			(effects
				(font
					(size 1.27 1.27)
					(thickness 0.15)
				)
			)
		)
		(property "Author" "Antmicro"
			(at 370.253001 -36.409001 0)
			(layer "F.Fab")
			(hide yes)
			(effects
				(font
					(size 1 1)
					(thickness 0.15)
				)
			)
		)
		(property "Dielectric" ""
			(at 370.253001 -36.409001 0)
			(layer "F.Fab")
			(hide yes)
			(effects
				(font
					(size 1 1)
					(thickness 0.15)
				)
			)
		)
		(property "License" "Apache-2.0"
			(at 370.253001 -36.409001 0)
			(layer "F.Fab")
			(hide yes)
			(effects
				(font
					(size 1 1)
					(thickness 0.15)
				)
			)
		)
		(property "MPN" "CL21A226MAYNNNE"
			(at 370.253001 -36.409001 0)
			(layer "F.Fab")
			(hide yes)
			(effects
				(font
					(size 1 1)
					(thickness 0.15)
				)
			)
		)
		(property "Manufacturer" "Samsung Electro-Mechanics"
			(at 370.253001 -36.409001 0)
			(layer "F.Fab")
			(hide yes)
			(effects
				(font
					(size 1 1)
					(thickness 0.15)
				)
			)
		)
		(property "Val" "22u_25V"
			(at 370.253001 -36.409001 0)
			(layer "F.Fab")
			(hide yes)
			(effects
				(font
					(size 1 1)
					(thickness 0.15)
				)
			)
		)
		(property "Voltage" ""
			(at 370.253001 -36.409001 0)
			(layer "F.Fab")
			(hide yes)
			(effects
				(font
					(size 1 1)
					(thickness 0.15)
				)
			)
		)
		(sheetname "/Supply/")
		(sheetfile "supply.kicad_sch")
		(attr smd)
		(fp_line
			(start -0.3 -0.8)
			(end 0.3 -0.8)
			(stroke
				(width 0.15)
				(type solid)
			)
			(layer "F.SilkS")
		)
		(fp_line
			(start -0.3 0.8)
			(end 0.3 0.8)
			(stroke
				(width 0.15)
				(type solid)
			)
			(layer "F.SilkS")
		)
		(fp_rect
			(start -1.9 -0.93)
			(end 1.9 0.93)
			(stroke
				(width 0.05)
				(type solid)
			)
			(fill no)
			(layer "F.CrtYd")
		)
		(fp_rect
			(start -0.95 -0.675)
			(end 0.95 0.675)
			(stroke
				(width 0.15)
				(type solid)
			)
			(fill no)
			(layer "F.Fab")
		)
		(pad "1" smd rect
			(at -1.05 0 90)
			(size 1.2 1.2)
			(layers "F.Cu" "F.Mask" "F.Paste")
			(net 1 "GND")
			(pintype "passive")
		)
		(pad "2" smd rect
			(at 1.05 0 90)
			(size 1.2 1.2)
			(layers "F.Cu" "F.Mask" "F.Paste")
			(net 38 "VDC")
			(pintype "passive")
		)
	)
	(footprint "antmicro-footprints:LED_0603_1608Metric_G"
		(layer "F.Cu")
		(at 94.3 197.1 -90)
		(descr "LED SMD 0603 Green")
		(tags "LED SMD 0603 Green")
		(property "Reference" "D11"
			(at -0.001 -0.901 270)
			(layer "F.SilkS")
			(hide yes)
			(effects
				(font
					(size 0.7 0.7)
					(thickness 0.15)
				)
				(justify left bottom)
			)
		)
		(property "Value" "LED_G_0603_KP-1608CGCK"
			(at -0.001 1.599 270)
			(layer "F.Fab")
			(effects
				(font
					(size 0.7 0.7)
					(thickness 0.15)
				)
				(justify left bottom)
			)
		)
		(property "Datasheet" "http://www.farnell.com/datasheets/2045956.pdf"
			(at 0 0 270)
			(layer "F.Fab")
			(hide yes)
			(effects
				(font
					(size 1.27 1.27)
					(thickness 0.15)
				)
			)
		)
		(property "Author" "Antmicro"
			(at -102.8 291.4 0)
			(layer "F.Fab")
			(hide yes)
			(effects
				(font
					(size 1 1)
					(thickness 0.15)
				)
			)
		)
		(property "License" "Apache-2.0"
			(at -102.8 291.4 0)
			(layer "F.Fab")
			(hide yes)
			(effects
				(font
					(size 1 1)
					(thickness 0.15)
				)
			)
		)
		(property "MPN" "KP-1608CGCK"
			(at -102.8 291.4 0)
			(layer "F.Fab")
			(hide yes)
			(effects
				(font
					(size 1 1)
					(thickness 0.15)
				)
			)
		)
		(property "Manufacturer" "Kingbright"
			(at -102.8 291.4 0)
			(layer "F.Fab")
			(hide yes)
			(effects
				(font
					(size 1 1)
					(thickness 0.15)
				)
			)
		)
		(sheetname "/Debug FTDI/")
		(sheetfile "debug-ftdi.kicad_sch")
		(attr smd)
		(fp_line
			(start -0.271 0.348)
			(end 0.269 0.348)
			(stroke
				(width 0.15)
				(type solid)
			)
			(layer "F.SilkS")
		)
		(fp_line
			(start 1.249 0.319)
			(end 1.249 -0.321)
			(stroke
				(width 0.15)
				(type solid)
			)
			(layer "F.SilkS")
		)
		(fp_line
			(start -0.107 -0.001)
			(end -0.291 -0.001)
			(stroke
				(width 0.1)
				(type solid)
			)
			(layer "F.SilkS")
		)
		(fp_line
			(start 0.092 -0.001)
			(end -0.107 0.198)
			(stroke
				(width 0.1)
				(type solid)
			)
			(layer "F.SilkS")
		)
		(fp_line
			(start 0.092 -0.001)
			(end 0.292 -0.001)
			(stroke
				(width 0.1)
				(type solid)
			)
			(layer "F.SilkS")
		)
		(fp_line
			(start -0.107 -0.201)
			(end -0.107 0.198)
			(stroke
				(width 0.1)
				(type solid)
			)
			(layer "F.SilkS")
		)
		(fp_line
			(start -0.107 -0.201)
			(end 0.092 -0.001)
			(stroke
				(width 0.1)
				(type solid)
			)
			(layer "F.SilkS")
		)
		(fp_line
			(start 0.092 -0.201)
			(end 0.092 0.198)
			(stroke
				(width 0.1)
				(type solid)
			)
			(layer "F.SilkS")
		)
		(fp_line
			(start -0.271 -0.349)
			(end 0.269 -0.349)
			(stroke
				(width 0.15)
				(type solid)
			)
			(layer "F.SilkS")
		)
		(fp_rect
			(start -1.2192 -0.6096)
			(end 1.27 0.6016)
			(stroke
				(width 0.05)
				(type solid)
			)
			(fill no)
			(layer "F.CrtYd")
		)
		(fp_line
			(start -0.202 0.201)
			(end 0.1 -0.001)
			(stroke
				(width 0.15)
				(type solid)
			)
			(layer "F.Fab")
		)
		(fp_line
			(start 0.198 0.201)
			(end 0.198 -0.101)
			(stroke
				(width 0.15)
				(type solid)
			)
			(layer "F.Fab")
		)
		(fp_line
			(start -0.849 0.025)
			(end -0.442 0.381)
			(stroke
				(width 0.15)
				(type solid)
			)
			(layer "F.Fab")
		)
		(fp_line
			(start -0.6 -0.001)
			(end -0.202 -0.001)
			(stroke
				(width 0.15)
				(type solid)
			)
			(layer "F.Fab")
		)
		(fp_line
			(start -0.202 -0.001)
			(end -0.202 0.201)
			(stroke
				(width 0.15)
				(type solid)
			)
			(layer "F.Fab")
		)
		(fp_line
			(start 0.1 -0.001)
			(end -0.202 -0.201)
			(stroke
				(width 0.15)
				(type solid)
			)
			(layer "F.Fab")
		)
		(fp_line
			(start 0.198 -0.001)
			(end 0.596 -0.001)
			(stroke
				(width 0.15)
				(type solid)
			)
			(layer "F.Fab")
		)
		(fp_line
			(start -0.202 -0.201)
			(end -0.202 -0.001)
			(stroke
				(width 0.15)
				(type solid)
			)
			(layer "F.Fab")
		)
		(fp_line
			(start 0.198 -0.201)
			(end 0.198 -0.101)
			(stroke
				(width 0.15)
				(type solid)
			)
			(layer "F.Fab")
		)
		(fp_rect
			(start -0.849 -0.401)
			(end 0.849 0.401)
			(stroke
				(width 0.15)
				(type solid)
			)
			(fill no)
			(layer "F.Fab")
		)
		(pad "1" smd rect
			(at -0.751 -0.001 90)
			(size 0.8 0.8)
			(layers "F.Cu" "F.Mask" "F.Paste")
			(net 316 "Net-(D11-Pad1)")
			(pinfunction "1")
			(pintype "passive")
		)
		(pad "2" smd rect
			(at 0.749 -0.001 90)
			(size 0.8 0.8)
			(layers "F.Cu" "F.Mask" "F.Paste")
			(net 1 "GND")
			(pinfunction "2")
			(pintype "passive")
		)
	)
	(footprint "antmicro-footprints:R_0402_1005Metric"
		(layer "F.Cu")
		(at 97.9 194.815 90)
		(descr "Resistor SMD 0402")
		(tags "resistor SMD 0402")
		(property "Reference" "R67"
			(at -1.122484 -0.772697 90)
			(layer "F.SilkS")
			(hide yes)
			(effects
				(font
					(size 0.7 0.7)
					(thickness 0.15)
				)
				(justify left bottom)
			)
		)
		(property "Value" "R_330R_0402"
			(at -1.011843 1.772047 90)
			(layer "F.Fab")
			(effects
				(font
					(size 0.7 0.7)
					(thickness 0.15)
				)
				(justify left bottom)
			)
		)
		(property "Datasheet" "https://www.bourns.com/docs/product-datasheets/cr.pdf"
			(at 0 0 90)
			(layer "F.Fab")
			(hide yes)
			(effects
				(font
					(size 1.27 1.27)
					(thickness 0.15)
				)
			)
		)
		(property "Author" "Antmicro"
			(at 292.715 96.915 0)
			(layer "F.Fab")
			(hide yes)
			(effects
				(font
					(size 1 1)
					(thickness 0.15)
				)
			)
		)
		(property "License" "Apache-2.0"
			(at 292.715 96.915 0)
			(layer "F.Fab")
			(hide yes)
			(effects
				(font
					(size 1 1)
					(thickness 0.15)
				)
			)
		)
		(property "MPN" "CR0402-FX-3300GLF"
			(at 292.715 96.915 0)
			(layer "F.Fab")
			(hide yes)
			(effects
				(font
					(size 1 1)
					(thickness 0.15)
				)
			)
		)
		(property "Manufacturer" "Bourns"
			(at 292.715 96.915 0)
			(layer "F.Fab")
			(hide yes)
			(effects
				(font
					(size 1 1)
					(thickness 0.15)
				)
			)
		)
		(property "Tolerance" "1%"
			(at 292.715 96.915 0)
			(layer "F.Fab")
			(hide yes)
			(effects
				(font
					(size 1 1)
					(thickness 0.15)
				)
			)
		)
		(property "Val" "330R"
			(at 292.715 96.915 0)
			(layer "F.Fab")
			(hide yes)
			(effects
				(font
					(size 1 1)
					(thickness 0.15)
				)
			)
		)
		(sheetname "/Debug FTDI/")
		(sheetfile "debug-ftdi.kicad_sch")
		(attr smd)
		(fp_rect
			(start -0.93 -0.47)
			(end 0.93 0.47)
			(stroke
				(width 0.05)
				(type solid)
			)
			(fill no)
			(layer "F.CrtYd")
		)
		(fp_rect
			(start -0.5 -0.25)
			(end 0.5 0.25)
			(stroke
				(width 0.15)
				(type solid)
			)
			(fill no)
			(layer "F.Fab")
		)
		(pad "1" smd roundrect
			(at -0.485 0 90)
			(size 0.59 0.64)
			(layers "F.Cu" "F.Mask" "F.Paste")
			(roundrect_rratio 0.25)
			(net 318 "Net-(D13-Pad1)")
			(pintype "passive")
		)
		(pad "2" smd roundrect
			(at 0.485 0 90)
			(size 0.59 0.64)
			(layers "F.Cu" "F.Mask" "F.Paste")
			(roundrect_rratio 0.25)
			(net 659 "/Debug FTDI/LED_RX1")
			(pintype "passive")
		)
	)
	(footprint "antmicro-footprints:SOT-23-6"
		(layer "F.Cu")
		(at 196.515 146.851 90)
		(property "Reference" "U31"
			(at -1.449 2.785 90)
			(layer "F.SilkS")
			(effects
				(font
					(size 0.7 0.7)
					(thickness 0.15)
				)
				(justify left bottom)
			)
		)
		(property "Value" "LM3880"
			(at -1.75 2.75 90)
			(layer "F.Fab")
			(effects
				(font
					(size 0.7 0.7)
					(thickness 0.15)
				)
				(justify left bottom)
			)
		)
		(property "Datasheet" "http://www.ti.com/lit/ds/symlink/lm3880.pdf"
			(at 0 0 90)
			(layer "F.Fab")
			(hide yes)
			(effects
				(font
					(size 1.27 1.27)
					(thickness 0.15)
				)
			)
		)
		(property "Author" "Antmicro"
			(at 343.366 -49.664 0)
			(layer "F.Fab")
			(hide yes)
			(effects
				(font
					(size 1 1)
					(thickness 0.15)
				)
			)
		)
		(property "License" "Apache-2.0"
			(at 343.366 -49.664 0)
			(layer "F.Fab")
			(hide yes)
			(effects
				(font
					(size 1 1)
					(thickness 0.15)
				)
			)
		)
		(property "MPN" "LM3880MFX-1AA/NOPB"
			(at 343.366 -49.664 0)
			(layer "F.Fab")
			(hide yes)
			(effects
				(font
					(size 1 1)
					(thickness 0.15)
				)
			)
		)
		(property "Manufacturer" "Texas Instruments"
			(at 343.366 -49.664 0)
			(layer "F.Fab")
			(hide yes)
			(effects
				(font
					(size 1 1)
					(thickness 0.15)
				)
			)
		)
		(property ki_fp_filters "SOT?23*")
		(sheetname "/Supply/")
		(sheetfile "supply.kicad_sch")
		(attr smd)
		(fp_line
			(start 1.45 -0.7)
			(end 1.45 -0.4)
			(stroke
				(width 0.12)
				(type solid)
			)
			(layer "F.SilkS")
		)
		(fp_line
			(start 1.3 -0.7)
			(end 1.45 -0.7)
			(stroke
				(width 0.12)
				(type solid)
			)
			(layer "F.SilkS")
		)
		(fp_line
			(start -1.3 -0.7)
			(end -1.45 -0.7)
			(stroke
				(width 0.12)
				(type solid)
			)
			(layer "F.SilkS")
		)
		(fp_line
			(start -1.45 -0.7)
			(end -1.45 -0.4)
			(stroke
				(width 0.12)
				(type solid)
			)
			(layer "F.SilkS")
		)
		(fp_line
			(start 1.45 0.7)
			(end 1.45 0.4)
			(stroke
				(width 0.12)
				(type solid)
			)
			(layer "F.SilkS")
		)
		(fp_line
			(start 1.3 0.7)
			(end 1.45 0.7)
			(stroke
				(width 0.12)
				(type solid)
			)
			(layer "F.SilkS")
		)
		(fp_line
			(start -1.45 0.7)
			(end -1.45 0.4)
			(stroke
				(width 0.12)
				(type solid)
			)
			(layer "F.SilkS")
		)
		(fp_rect
			(start -1.55 -1.85)
			(end 1.55 1.75)
			(stroke
				(width 0.05)
				(type solid)
			)
			(fill no)
			(layer "F.CrtYd")
		)
		(fp_line
			(start 1.5 -0.7)
			(end 1.5 0.7)
			(stroke
				(width 0.1)
				(type solid)
			)
			(layer "F.Fab")
		)
		(fp_line
			(start -1.5 -0.7)
			(end 1.5 -0.7)
			(stroke
				(width 0.1)
				(type solid)
			)
			(layer "F.Fab")
		)
		(fp_line
			(start 1.5 0.7)
			(end -1.5 0.7)
			(stroke
				(width 0.1)
				(type solid)
			)
			(layer "F.Fab")
		)
		(fp_line
			(start -1.5 0.7)
			(end -1.5 -0.7)
			(stroke
				(width 0.1)
				(type solid)
			)
			(layer "F.Fab")
		)
		(fp_text user "."
			(at -1.4 1.2 270)
			(layer "F.SilkS")
			(effects
				(font
					(size 1 1)
					(thickness 0.15)
				)
			)
		)
		(pad "1" smd roundrect
			(at -0.954 1.1 90)
			(size 0.55 1)
			(layers "F.Cu" "F.Mask" "F.Paste")
			(roundrect_rratio 0.15)
			(net 41 "+3V3_AON")
			(pinfunction "VCC")
			(pintype "power_in")
		)
		(pad "2" smd roundrect
			(at -0.003 1.1 90)
			(size 0.55 1)
			(layers "F.Cu" "F.Mask" "F.Paste")
			(roundrect_rratio 0.15)
			(net 1 "GND")
			(pinfunction "GND")
			(pintype "power_in")
		)
		(pad "3" smd roundrect
			(at 0.947 1.1 90)
			(size 0.55 1)
			(layers "F.Cu" "F.Mask" "F.Paste")
			(roundrect_rratio 0.15)
			(net 62 "/Supply/SEQ_EN")
			(pinfunction "EN")
			(pintype "input")
		)
		(pad "4" smd roundrect
			(at 0.947 -1.214 90)
			(size 0.55 1)
			(layers "F.Cu" "F.Mask" "F.Paste")
			(roundrect_rratio 0.15)
			(net 223 "/Supply/EN3")
			(pinfunction "FLAG3")
			(pintype "open_collector")
		)
		(pad "5" smd roundrect
			(at -0.003 -1.214 90)
			(size 0.55 1)
			(layers "F.Cu" "F.Mask" "F.Paste")
			(roundrect_rratio 0.15)
			(net 222 "/Supply/EN2")
			(pinfunction "FLAG2")
			(pintype "open_collector")
		)
		(pad "6" smd roundrect
			(at -0.954 -1.214 90)
			(size 0.55 1)
			(layers "F.Cu" "F.Mask" "F.Paste")
			(roundrect_rratio 0.15)
			(net 221 "/Supply/EN1")
			(pinfunction "FLAG1")
			(pintype "open_collector")
		)
	)
	(footprint "antmicro-footprints:NetTie-2_SMD_Pad0.127mm"
		(layer "F.Cu")
		(at 200.325 177.174)
		(descr "Net tie, 2 pin, 0.127mm  SMD pads")
		(tags "net tie")
		(property "Reference" "NT3"
			(at -0.128 -1.345 0)
			(layer "F.SilkS")
			(hide yes)
			(effects
				(font
					(size 0.7 0.7)
					(thickness 0.15)
				)
				(justify left bottom)
			)
		)
		(property "Value" "Net-Tie_P0.127mm"
			(at 0 1.199 0)
			(layer "F.Fab")
			(effects
				(font
					(size 0.7 0.7)
					(thickness 0.15)
				)
				(justify left bottom)
			)
		)
		(property "Author" "Antmicro"
			(at 0 0 0)
			(layer "F.Fab")
			(hide yes)
			(effects
				(font
					(size 1 1)
					(thickness 0.15)
				)
			)
		)
		(property "License" "Apache-2.0"
			(at 0 0 0)
			(layer "F.Fab")
			(hide yes)
			(effects
				(font
					(size 1 1)
					(thickness 0.15)
				)
			)
		)
		(property "MPN" ""
			(at 0 0 0)
			(layer "F.Fab")
			(hide yes)
			(effects
				(font
					(size 1 1)
					(thickness 0.15)
				)
			)
		)
		(property "Manufacturer" ""
			(at 0 0 0)
			(layer "F.Fab")
			(hide yes)
			(effects
				(font
					(size 1 1)
					(thickness 0.15)
				)
			)
		)
		(property ki_fp_filters "Net*Tie*")
		(sheetname "/Supply/")
		(sheetfile "supply.kicad_sch")
		(attr smd exclude_from_pos_files exclude_from_bom)
		(net_tie_pad_groups "1, 2")
		(fp_poly
			(pts
				(xy -0.0635 -0.0635) (xy 0.0625 -0.0635) (xy 0.0625 0.0635) (xy -0.0635 0.0635)
			)
			(stroke
				(width 0)
				(type solid)
			)
			(fill yes)
			(layer "F.Cu")
		)
		(pad "1" smd roundrect
			(at -0.127 0 180)
			(size 0.127 0.127)
			(layers "F.Cu")
			(roundrect_rratio 0.5)
			(chamfer_ratio 0)
			(chamfer top_left bottom_left)
			(net 232 "/Supply/sp_SEN_+")
			(pinfunction "1")
			(pintype "passive")
		)
		(pad "2" smd roundrect
			(at 0.126 0)
			(size 0.127 0.127)
			(layers "F.Cu")
			(roundrect_rratio 0.5)
			(chamfer_ratio 0)
			(chamfer top_left bottom_left)
			(net 35 "/Supply/spare_local")
			(pinfunction "2")
			(pintype "passive")
		)
	)
)
